# T6G (Grand Teton) — schematic netlist excerpt (pin names and nets, part order shuffled) for the footprints in the layout excerpt that follows; sources: Cadence DE-HDL packaged netlist, KiCad conversion of 04192023_DAF0TMB3IC0_F0TG_MB_C_brd_V02_OCP.brd

C1069  Q_CAP  0.1UF 10V 10% X7S  pkg C0201  page 186 : A = P3V3_AUX ; B = GND
R9033  Q_RES  33.2 1% CHIP  pkg 0402LF  page 136 : A = RST_PERST_OCP_SFF_BUF_R_N ; B = RST_PERST_OCP_SFF_BUF_N
R1547  Q_RES  4.7K 5% CHIP  pkg 0402LF  page 77 : A = P3V3_AUX ; B = SPI_CPU0_LVC3_TPM_CS_N

(kicad_pcb
	(version 20260206)
	(generator "pcbnew")
	(generator_version "10.0")
	(general
		(thickness 1.6)
		(legacy_teardrops no)
	)
	(paper "A4")
	(title_block
		(title "04192023_DAF0TMB3IC0_F0TG_MB_C_brd_V02_OCP.brd")
		(comment 1 "Grand Teton / footprints 246-248 of 8354")
	)
	(layers
		(0 "F.Cu" signal "TOP")
		(4 "In1.Cu" signal "GND")
		(6 "In2.Cu" signal "IN1")
		(8 "In3.Cu" signal "GND1")
		(10 "In4.Cu" signal "IN2")
		(12 "In5.Cu" signal "GND2")
		(14 "In6.Cu" signal "IN3")
		(16 "In7.Cu" signal "GND3")
		(18 "In8.Cu" signal "VCC")
		(20 "In9.Cu" signal "VCC1")
		(22 "In10.Cu" signal "GND4")
		(24 "In11.Cu" signal "IN4")
		(26 "In12.Cu" signal "GND5")
		(28 "In13.Cu" signal "IN5")
		(30 "In14.Cu" signal "GND6")
		(32 "In15.Cu" signal "IN6")
		(34 "In16.Cu" signal "GND7")
		(2 "B.Cu" signal "BOTTOM")
		(9 "F.Adhes" user "F.Adhesive")
		(11 "B.Adhes" user "B.Adhesive")
		(13 "F.Paste" user "Package Geometry/Pastemask Top")
		(15 "B.Paste" user "Package Geometry/Pastemask Bottom")
		(5 "F.SilkS" user "Ref Des/Silkscreen Top")
		(7 "B.SilkS" user "Ref Des/Silkscreen Bottom")
		(1 "F.Mask" user "Board Geometry/Soldermask Top")
		(3 "B.Mask" user "Board Geometry/Soldermask Bottom")
		(17 "Dwgs.User" user "User.Drawings")
		(19 "Cmts.User" user "User.Comments")
		(21 "Eco1.User" user "User.Eco1")
		(23 "Eco2.User" user "User.Eco2")
		(25 "Edge.Cuts" user "Board Geometry/Outline")
		(27 "Margin" user)
		(31 "F.CrtYd" user "Package Geometry/Place Bound Top")
		(29 "B.CrtYd" user "Package Geometry/Place Bound Bottom")
		(35 "F.Fab" user "Ref Des/Assembly Top")
		(33 "B.Fab" user "Ref Des/Assembly Bottom")
	)
	(footprint ""
		(layer "F.Cu")
		(at 251.474224 -134.892796)
		(property "Reference" "R1547"
			(at 0 0 0)
			(layer "F.SilkS")
			(hide yes)
			(effects
				(font
					(size 1.27 1.27)
				)
			)
		)
		(property "Value" ""
			(at 0 0 0)
			(layer "F.Fab")
			(effects
				(font
					(size 1.27 1.27)
				)
			)
		)
		(duplicate_pad_numbers_are_jumpers no)
		(fp_line
			(start -0.7874 -0.4064)
			(end 0.7874 -0.4064)
			(stroke
				(width 0.1524)
				(type default)
			)
			(layer "F.SilkS")
		)
		(fp_line
			(start -0.7874 0.4064)
			(end -0.7874 -0.4064)
			(stroke
				(width 0.1524)
				(type default)
			)
			(layer "F.SilkS")
		)
		(fp_line
			(start 0.7874 -0.4064)
			(end 0.7874 0.4064)
			(stroke
				(width 0.1524)
				(type default)
			)
			(layer "F.SilkS")
		)
		(fp_line
			(start 0.7874 0.4064)
			(end -0.7874 0.4064)
			(stroke
				(width 0.1524)
				(type default)
			)
			(layer "F.SilkS")
		)
		(fp_line
			(start -0.67945 -0.305054)
			(end -0.12065 -0.305054)
			(stroke
				(width 0.1)
				(type default)
			)
			(layer "F.Fab")
		)
		(fp_line
			(start -0.67945 0.3048)
			(end -0.67945 -0.305054)
			(stroke
				(width 0.1)
				(type default)
			)
			(layer "F.Fab")
		)
		(fp_line
			(start -0.12065 -0.305054)
			(end -0.12065 -0.2794)
			(stroke
				(width 0.1)
				(type default)
			)
			(layer "F.Fab")
		)
		(fp_line
			(start -0.12065 -0.2794)
			(end 0.12065 -0.2794)
			(stroke
				(width 0.1)
				(type default)
			)
			(layer "F.Fab")
		)
		(fp_line
			(start -0.12065 0.2794)
			(end -0.12065 0.3048)
			(stroke
				(width 0.1)
				(type default)
			)
			(layer "F.Fab")
		)
		(fp_line
			(start -0.12065 0.3048)
			(end -0.67945 0.3048)
			(stroke
				(width 0.1)
				(type default)
			)
			(layer "F.Fab")
		)
		(fp_line
			(start 0.120396 0.2794)
			(end -0.12065 0.2794)
			(stroke
				(width 0.1)
				(type default)
			)
			(layer "F.Fab")
		)
		(fp_line
			(start 0.120396 0.3048)
			(end 0.120396 0.2794)
			(stroke
				(width 0.1)
				(type default)
			)
			(layer "F.Fab")
		)
		(fp_line
			(start 0.12065 -0.3048)
			(end 0.67945 -0.3048)
			(stroke
				(width 0.1)
				(type default)
			)
			(layer "F.Fab")
		)
		(fp_line
			(start 0.12065 -0.2794)
			(end 0.12065 -0.3048)
			(stroke
				(width 0.1)
				(type default)
			)
			(layer "F.Fab")
		)
		(fp_line
			(start 0.67945 -0.3048)
			(end 0.67945 0.3048)
			(stroke
				(width 0.1)
				(type default)
			)
			(layer "F.Fab")
		)
		(fp_line
			(start 0.67945 0.3048)
			(end 0.120396 0.3048)
			(stroke
				(width 0.1)
				(type default)
			)
			(layer "F.Fab")
		)
		(pad "1" smd circle
			(at -0.40005 0)
			(size 0 0)
			(layers "F.Cu" "F.Mask" "F.Paste")
			(net "P3V3_AUX")
		)
		(pad "2" smd circle
			(at 0.40005 0)
			(size 0 0)
			(layers "F.Cu" "F.Mask" "F.Paste")
			(net "SPI_CPU0_LVC3_TPM_CS_N")
		)
	)
	(footprint ""
		(layer "F.Cu")
		(at 216.408 -123.825 90)
		(property "Reference" "R9033"
			(at 0 0 90)
			(layer "F.SilkS")
			(hide yes)
			(effects
				(font
					(size 1.27 1.27)
				)
			)
		)
		(property "Value" ""
			(at 0 0 90)
			(layer "F.Fab")
			(effects
				(font
					(size 1.27 1.27)
				)
			)
		)
		(duplicate_pad_numbers_are_jumpers no)
		(fp_line
			(start 0.7874 -0.4064)
			(end 0.7874 0.4064)
			(stroke
				(width 0.1524)
				(type default)
			)
			(layer "F.SilkS")
		)
		(fp_line
			(start -0.7874 -0.4064)
			(end 0.7874 -0.4064)
			(stroke
				(width 0.1524)
				(type default)
			)
			(layer "F.SilkS")
		)
		(fp_line
			(start 0.7874 0.4064)
			(end -0.7874 0.4064)
			(stroke
				(width 0.1524)
				(type default)
			)
			(layer "F.SilkS")
		)
		(fp_line
			(start -0.7874 0.4064)
			(end -0.7874 -0.4064)
			(stroke
				(width 0.1524)
				(type default)
			)
			(layer "F.SilkS")
		)
		(fp_line
			(start -0.12065 -0.305054)
			(end -0.12065 -0.2794)
			(stroke
				(width 0.1)
				(type default)
			)
			(layer "F.Fab")
		)
		(fp_line
			(start -0.67945 -0.305054)
			(end -0.12065 -0.305054)
			(stroke
				(width 0.1)
				(type default)
			)
			(layer "F.Fab")
		)
		(fp_line
			(start 0.67945 -0.3048)
			(end 0.67945 0.3048)
			(stroke
				(width 0.1)
				(type default)
			)
			(layer "F.Fab")
		)
		(fp_line
			(start 0.12065 -0.3048)
			(end 0.67945 -0.3048)
			(stroke
				(width 0.1)
				(type default)
			)
			(layer "F.Fab")
		)
		(fp_line
			(start 0.12065 -0.2794)
			(end 0.12065 -0.3048)
			(stroke
				(width 0.1)
				(type default)
			)
			(layer "F.Fab")
		)
		(fp_line
			(start -0.12065 -0.2794)
			(end 0.12065 -0.2794)
			(stroke
				(width 0.1)
				(type default)
			)
			(layer "F.Fab")
		)
		(fp_line
			(start 0.120396 0.2794)
			(end -0.12065 0.2794)
			(stroke
				(width 0.1)
				(type default)
			)
			(layer "F.Fab")
		)
		(fp_line
			(start -0.12065 0.2794)
			(end -0.12065 0.3048)
			(stroke
				(width 0.1)
				(type default)
			)
			(layer "F.Fab")
		)
		(fp_line
			(start 0.67945 0.3048)
			(end 0.120396 0.3048)
			(stroke
				(width 0.1)
				(type default)
			)
			(layer "F.Fab")
		)
		(fp_line
			(start 0.120396 0.3048)
			(end 0.120396 0.2794)
			(stroke
				(width 0.1)
				(type default)
			)
			(layer "F.Fab")
		)
		(fp_line
			(start -0.12065 0.3048)
			(end -0.67945 0.3048)
			(stroke
				(width 0.1)
				(type default)
			)
			(layer "F.Fab")
		)
		(fp_line
			(start -0.67945 0.3048)
			(end -0.67945 -0.305054)
			(stroke
				(width 0.1)
				(type default)
			)
			(layer "F.Fab")
		)
		(pad "1" smd circle
			(at -0.40005 0 90)
			(size 0 0)
			(layers "F.Cu" "F.Mask" "F.Paste")
			(net "RST_PERST_OCP_SFF_BUF_R_N")
		)
		(pad "2" smd circle
			(at 0.40005 0 90)
			(size 0 0)
			(layers "F.Cu" "F.Mask" "F.Paste")
			(net "RST_PERST_OCP_SFF_BUF_N")
		)
	)
	(footprint ""
		(layer "F.Cu")
		(at 97.652078 -404.593044 90)
		(property "Reference" "C1069"
			(at 0 0 90)
			(layer "F.SilkS")
			(hide yes)
			(effects
				(font
					(size 1.27 1.27)
				)
			)
		)
		(property "Value" ""
			(at 0 0 90)
			(layer "F.Fab")
			(effects
				(font
					(size 1.27 1.27)
				)
			)
		)
		(duplicate_pad_numbers_are_jumpers no)
		(fp_line
			(start 0.299974 -0.150114)
			(end 0.299974 0.150114)
			(stroke
				(width 0.1)
				(type default)
			)
			(layer "F.Fab")
		)
		(fp_line
			(start -0.299974 -0.150114)
			(end 0.299974 -0.150114)
			(stroke
				(width 0.1)
				(type default)
			)
			(layer "F.Fab")
		)
		(fp_line
			(start 0.299974 0.150114)
			(end -0.299974 0.150114)
			(stroke
				(width 0.1)
				(type default)
			)
			(layer "F.Fab")
		)
		(fp_line
			(start -0.299974 0.150114)
			(end -0.299974 -0.150114)
			(stroke
				(width 0.1)
				(type default)
			)
			(layer "F.Fab")
		)
		(pad "1" smd rect
			(at -0.2667 0 90)
			(size 0.3048 0.381)
			(layers "F.Cu" "F.Mask" "F.Paste")
			(net "P3V3_AUX")
		)
		(pad "2" smd rect
			(at 0.2667 0 90)
			(size 0.3048 0.381)
			(layers "F.Cu" "F.Mask" "F.Paste")
			(net "GND")
		)
	)
)
